# BARRELEYE-G2-EXPANDER-EVT-HW-EBOM-X00-20161124-add_2nd_source_X06-20161207-Final.xls — Component Qual Tracker (bom)
|  |  |  |  |  |  |  |  | Part to be included on following build: |  |  |  |  |  |
| Item No. | Part Group | Single/Sole/Multi | Item Description | ODM P/N | Customer PN | Vendor | Vendor P/N | X00 Build | X01 Build | X02 Build | Qual Build | Qualification Target Date | Qualification Complete Date |
|  | VR Controllers |  |  |  |  | Vendor #1 |  |  |  |  |  |  |  |
|  |  |  |  |  |  | Vendor #2 |  |  |  |  |  |  |  |
|  | FETS |  |  |  |  | Vendor #1 |  |  |  |  |  |  |  |
|  |  |  |  |  |  | Vendor #2 |  |  |  |  |  |  |  |
|  | INDUCTORS |  |  |  |  | Vendor #1 |  |  |  |  |  |  |  |
|  |  |  |  |  |  | Vendor #2 |  |  |  |  |  |  |  |
|  | VREG CAPS |  |  |  |  | Vendor #1 |  |  |  |  |  |  |  |
|  |  |  |  |  |  | Vendor #2 |  |  |  |  |  |  |  |
|  | CRYSTALS |  |  |  |  | Vendor #1 |  |  |  |  |  |  |  |
|  |  |  |  |  |  | Vendor #2 |  |  |  |  |  |  |  |
|  | CONNECTORS |  |  |  |  | Vendor #1 |  |  |  |  |  |  |  |
|  |  |  |  |  |  | Vendor #2 |  |  |  |  |  |  |  |
|  | IC'S |  |  |  |  | Vendor #1 |  |  |  |  |  |  |  |
|  |  |  |  |  |  | Vendor #2 |  |  |  |  |  |  |  |
|  | MISC. |  |  |  |  | Vendor #1 |  |  |  |  |  |  |  |
|  | (HEATSINKS) |  |  |  |  | Vendor #2 |  |  |  |  |  |  |  |
